(kicad_pcb
	(version 20260206)
	(generator "pcbnew")
	(generator_version "10.0")
	(general
		(thickness 1.6)
		(legacy_teardrops no)
	)
	(paper "A4")
	(title_block
		(title "baseboard — 13948-1b.1110WZS1818.brd")
		(comment 1 "Honey Badger (Wiwynn) / footprints 1914-1921 of 2523")
	)
	(layers
		(0 "F.Cu" signal "TOP")
		(4 "In1.Cu" signal "L2GND")
		(6 "In2.Cu" signal "L3")
		(8 "In3.Cu" signal "L4VCC")
		(10 "In4.Cu" signal "L5VCC")
		(12 "In5.Cu" signal "L6")
		(14 "In6.Cu" signal "L7GND")
		(2 "B.Cu" signal "BOTTOM")
		(9 "F.Adhes" user "F.Adhesive")
		(11 "B.Adhes" user "B.Adhesive")
		(13 "F.Paste" user "Package Geometry/Pastemask Top")
		(15 "B.Paste" user "Package Geometry/Pastemask Bottom")
		(5 "F.SilkS" user "Ref Des/Silkscreen Top")
		(7 "B.SilkS" user "Ref Des/Silkscreen Bottom")
		(1 "F.Mask" user "Board Geometry/Soldermask Top")
		(3 "B.Mask" user "Board Geometry/Soldermask Bottom")
		(17 "Dwgs.User" user "User.Drawings")
		(19 "Cmts.User" user "User.Comments")
		(21 "Eco1.User" user "User.Eco1")
		(23 "Eco2.User" user "User.Eco2")
		(25 "Edge.Cuts" user "Board Geometry/Outline")
		(27 "Margin" user)
		(31 "F.CrtYd" user "Package Geometry/Place Bound Top")
		(29 "B.CrtYd" user "Package Geometry/Place Bound Bottom")
		(35 "F.Fab" user "Ref Des/Assembly Top")
		(33 "B.Fab" user "Ref Des/Assembly Bottom")
	)
	(footprint ""
		(layer "B.Cu")
		(at 124.568966 -33.401)
		(property "Reference" "SC931"
			(at 0 0 0)
			(layer "B.SilkS")
			(hide yes)
			(effects
				(font
					(size 1.27 1.27)
				)
				(justify mirror)
			)
		)
		(property "Value" "SC22U6D3V5MX-2GP"
			(at 0.0762 -6.1214 0)
			(unlocked yes)
			(layer "B.Fab")
			(hide yes)
			(effects
				(font
					(size 1.016 1.016)
					(thickness 0.1524)
				)
				(justify mirror)
			)
		)
		(property "Device Type" "C805H58"
			(at 0.0762 -8.1534 0)
			(unlocked yes)
			(layer "B.Fab")
			(hide yes)
			(effects
				(font
					(size 1.016 1.016)
					(thickness 0.1524)
				)
				(justify mirror)
			)
		)
		(duplicate_pad_numbers_are_jumpers no)
		(fp_line
			(start -0.635 0)
			(end 0.635 0)
			(stroke
				(width 0.508)
				(type default)
			)
			(layer "B.SilkS")
		)
		(fp_rect
			(start 0.9652 1.778)
			(end -0.9652 -1.778)
			(stroke
				(width 0)
				(type default)
			)
			(fill no)
			(layer "B.CrtYd")
		)
		(fp_poly
			(pts
				(xy 0.9652 -1.778) (xy -0.9652 -1.778) (xy -0.9652 1.778) (xy 0.9652 1.778)
			)
			(stroke
				(width 0)
				(type default)
			)
			(fill no)
			(layer "B.Fab")
		)
		(pad "1" smd rect
			(at 0 -0.9652 180)
			(size 1.397 1.143)
			(layers "B.Cu" "B.Mask" "B.Paste")
			(net "PLL_VDD")
		)
		(pad "2" smd rect
			(at 0 0.9652 180)
			(size 1.397 1.143)
			(layers "B.Cu" "B.Mask" "B.Paste")
			(net "GND")
		)
	)
	(footprint ""
		(layer "B.Cu")
		(at 286.4612 -166.675816)
		(property "Reference" "TP183"
			(at 0 0 0)
			(layer "B.SilkS")
			(hide yes)
			(effects
				(font
					(size 1.27 1.27)
				)
				(justify mirror)
			)
		)
		(property "Value" "TPAD28"
			(at -0.0127 -1.8034 0)
			(unlocked yes)
			(layer "B.Fab")
			(hide yes)
			(effects
				(font
					(size 1.016 1.016)
					(thickness 0.1524)
				)
				(justify mirror)
			)
		)
		(property "Device Type" "TPAD28"
			(at -0.0127 -3.3274 0)
			(unlocked yes)
			(layer "B.Fab")
			(hide yes)
			(effects
				(font
					(size 1.016 1.016)
					(thickness 0.1524)
				)
				(justify mirror)
			)
		)
		(duplicate_pad_numbers_are_jumpers no)
		(fp_poly
			(pts
				(arc
					(start 0.3556 0)
					(mid -0.3556 0)
					(end 0.3556 0)
				)
			)
			(stroke
				(width 0)
				(type default)
			)
			(fill no)
			(layer "B.CrtYd")
		)
		(fp_poly
			(pts
				(arc
					(start 0.6096 0)
					(mid -0.6096 0)
					(end 0.6096 0)
				)
			)
			(stroke
				(width 0)
				(type default)
			)
			(fill no)
			(layer "B.Fab")
		)
		(pad "1" smd circle
			(at 0 0 180)
			(size 0.7112 0.7112)
			(layers "B.Cu" "B.Mask" "B.Paste")
			(net "TP_BMC_GPIOF7")
		)
	)
	(footprint ""
		(layer "B.Cu")
		(at 69.514212 -244.856)
		(property "Reference" "C298"
			(at 0 0 0)
			(layer "B.SilkS")
			(hide yes)
			(effects
				(font
					(size 1.27 1.27)
				)
				(justify mirror)
			)
		)
		(property "Value" "SCD1U25V2KX-2-GP"
			(at -1.1811 -2.7051 0)
			(unlocked yes)
			(layer "B.Fab")
			(hide yes)
			(effects
				(font
					(size 1.016 1.016)
					(thickness 0.1524)
				)
				(justify mirror)
			)
		)
		(property "Device Type" "C402H22"
			(at -1.1811 -4.2291 0)
			(unlocked yes)
			(layer "B.Fab")
			(hide yes)
			(effects
				(font
					(size 1.016 1.016)
					(thickness 0.1524)
				)
				(justify mirror)
			)
		)
		(duplicate_pad_numbers_are_jumpers no)
		(fp_rect
			(start 0.4318 0.9525)
			(end -0.4318 -0.9525)
			(stroke
				(width 0)
				(type default)
			)
			(fill no)
			(layer "B.CrtYd")
		)
		(fp_rect
			(start 0.4318 0.9525)
			(end -0.4318 -0.9525)
			(stroke
				(width 0)
				(type default)
			)
			(fill no)
			(layer "B.Fab")
		)
		(pad "1" smd custom
			(at 0 -0.4445 180)
			(size 0.1524 0.1524)
			(layers "B.Cu" "B.Mask" "B.Paste")
			(net "P12V_PCIE")
			(options
				(clearance outline)
				(anchor circle)
			)
			(primitives
				(gr_poly
					(pts
						(arc
							(start 0.3048 0.2032)
							(mid 0.275042 0.275042)
							(end 0.2032 0.3048)
						)
						(arc
							(start -0.2032 0.3048)
							(mid -0.275042 0.275042)
							(end -0.3048 0.2032)
						)
						(arc
							(start -0.3048 -0.2032)
							(mid -0.275042 -0.275042)
							(end -0.2032 -0.3048)
						)
						(arc
							(start 0.2032 -0.3048)
							(mid 0.275042 -0.275042)
							(end 0.3048 -0.2032)
						)
					)
					(width 0)
					(fill yes)
				)
			)
		)
		(pad "2" smd custom
			(at 0 0.4445 180)
			(size 0.1524 0.1524)
			(layers "B.Cu" "B.Mask" "B.Paste")
			(net "GND")
			(options
				(clearance outline)
				(anchor circle)
			)
			(primitives
				(gr_poly
					(pts
						(arc
							(start 0.3048 0.2032)
							(mid 0.275042 0.275042)
							(end 0.2032 0.3048)
						)
						(arc
							(start -0.2032 0.3048)
							(mid -0.275042 0.275042)
							(end -0.3048 0.2032)
						)
						(arc
							(start -0.3048 -0.2032)
							(mid -0.275042 -0.275042)
							(end -0.2032 -0.3048)
						)
						(arc
							(start 0.2032 -0.3048)
							(mid 0.275042 -0.275042)
							(end 0.3048 -0.2032)
						)
					)
					(width 0)
					(fill yes)
				)
			)
		)
	)
	(footprint ""
		(layer "B.Cu")
		(at 307.086 -160.655 180)
		(property "Reference" "R465"
			(at 0 0 0)
			(layer "B.SilkS")
			(hide yes)
			(effects
				(font
					(size 1.27 1.27)
				)
				(justify mirror)
			)
		)
		(property "Value" "0R2J-2-GP"
			(at -0.064008 -3.993896 180)
			(unlocked yes)
			(layer "B.Fab")
			(hide yes)
			(effects
				(font
					(size 1.016 1.016)
					(thickness 0.1524)
				)
				(justify mirror)
			)
		)
		(property "Device Type" "R402H16"
			(at -0.064008 -5.517896 180)
			(unlocked yes)
			(layer "B.Fab")
			(hide yes)
			(effects
				(font
					(size 1.016 1.016)
					(thickness 0.1524)
				)
				(justify mirror)
			)
		)
		(duplicate_pad_numbers_are_jumpers no)
		(fp_line
			(start 0.508 -0.9398)
			(end 0.508 0.9398)
			(stroke
				(width 0.1524)
				(type default)
			)
			(layer "B.SilkS")
		)
		(fp_line
			(start -0.508 -0.9398)
			(end 0.508 -0.9398)
			(stroke
				(width 0.1524)
				(type default)
			)
			(layer "B.SilkS")
		)
		(fp_rect
			(start 0.508 0.9398)
			(end -0.508 -0.9398)
			(stroke
				(width 0)
				(type default)
			)
			(fill no)
			(layer "B.CrtYd")
		)
		(fp_rect
			(start 0.508 0.9398)
			(end -0.508 -0.9398)
			(stroke
				(width 0)
				(type default)
			)
			(fill no)
			(layer "B.Fab")
		)
		(pad "1" smd custom
			(at 0 -0.4445)
			(size 0.1397 0.1397)
			(layers "B.Cu" "B.Mask" "B.Paste")
			(net "BMC_I2C_SCL_9")
			(options
				(clearance outline)
				(anchor circle)
			)
			(primitives
				(gr_poly
					(pts
						(arc
							(start -0.1778 0.2794)
							(mid -0.249642 0.249642)
							(end -0.2794 0.1778)
						)
						(arc
							(start -0.2794 -0.1778)
							(mid -0.249642 -0.249642)
							(end -0.1778 -0.2794)
						)
						(arc
							(start 0.1778 -0.2794)
							(mid 0.249642 -0.249642)
							(end 0.2794 -0.1778)
						)
						(arc
							(start 0.2794 0.1778)
							(mid 0.249642 0.249642)
							(end 0.1778 0.2794)
						)
					)
					(width 0)
					(fill yes)
				)
			)
		)
		(pad "2" smd custom
			(at 0 0.4445)
			(size 0.1397 0.1397)
			(layers "B.Cu" "B.Mask" "B.Paste")
			(net "BMC0_SMB9_CLK")
			(options
				(clearance outline)
				(anchor circle)
			)
			(primitives
				(gr_poly
					(pts
						(arc
							(start -0.1778 0.2794)
							(mid -0.249642 0.249642)
							(end -0.2794 0.1778)
						)
						(arc
							(start -0.2794 -0.1778)
							(mid -0.249642 -0.249642)
							(end -0.1778 -0.2794)
						)
						(arc
							(start 0.1778 -0.2794)
							(mid 0.249642 -0.249642)
							(end 0.2794 -0.1778)
						)
						(arc
							(start 0.2794 0.1778)
							(mid 0.249642 0.249642)
							(end 0.1778 0.2794)
						)
					)
					(width 0)
					(fill yes)
				)
			)
		)
	)
	(footprint ""
		(layer "B.Cu")
		(at 15.571216 -170.10888 90)
		(property "Reference" "SC1111"
			(at 0 0 90)
			(layer "B.SilkS")
			(hide yes)
			(effects
				(font
					(size 1.27 1.27)
				)
				(justify mirror)
			)
		)
		(property "Value" "SCD1U16V2KX-3GP"
			(at -1.1811 -2.7051 90)
			(unlocked yes)
			(layer "B.Fab")
			(hide yes)
			(effects
				(font
					(size 1.016 1.016)
					(thickness 0.1524)
				)
				(justify mirror)
			)
		)
		(property "Device Type" "C402H22"
			(at -1.1811 -4.2291 90)
			(unlocked yes)
			(layer "B.Fab")
			(hide yes)
			(effects
				(font
					(size 1.016 1.016)
					(thickness 0.1524)
				)
				(justify mirror)
			)
		)
		(duplicate_pad_numbers_are_jumpers no)
		(fp_rect
			(start 0.4318 0.9525)
			(end -0.4318 -0.9525)
			(stroke
				(width 0)
				(type default)
			)
			(fill no)
			(layer "B.CrtYd")
		)
		(fp_rect
			(start 0.4318 0.9525)
			(end -0.4318 -0.9525)
			(stroke
				(width 0)
				(type default)
			)
			(fill no)
			(layer "B.Fab")
		)
		(pad "1" smd custom
			(at 0 -0.4445 270)
			(size 0.1524 0.1524)
			(layers "B.Cu" "B.Mask" "B.Paste")
			(net "P1V8_E")
			(options
				(clearance outline)
				(anchor circle)
			)
			(primitives
				(gr_poly
					(pts
						(arc
							(start 0.3048 0.2032)
							(mid 0.275042 0.275042)
							(end 0.2032 0.3048)
						)
						(arc
							(start -0.2032 0.3048)
							(mid -0.275042 0.275042)
							(end -0.3048 0.2032)
						)
						(arc
							(start -0.3048 -0.2032)
							(mid -0.275042 -0.275042)
							(end -0.2032 -0.3048)
						)
						(arc
							(start 0.2032 -0.3048)
							(mid 0.275042 -0.275042)
							(end 0.3048 -0.2032)
						)
					)
					(width 0)
					(fill yes)
				)
			)
		)
		(pad "2" smd custom
			(at 0 0.4445 270)
			(size 0.1524 0.1524)
			(layers "B.Cu" "B.Mask" "B.Paste")
			(net "GND")
			(options
				(clearance outline)
				(anchor circle)
			)
			(primitives
				(gr_poly
					(pts
						(arc
							(start 0.3048 0.2032)
							(mid 0.275042 0.275042)
							(end 0.2032 0.3048)
						)
						(arc
							(start -0.2032 0.3048)
							(mid -0.275042 0.275042)
							(end -0.3048 0.2032)
						)
						(arc
							(start -0.3048 -0.2032)
							(mid -0.275042 -0.275042)
							(end -0.2032 -0.3048)
						)
						(arc
							(start 0.2032 -0.3048)
							(mid 0.275042 -0.275042)
							(end 0.3048 -0.2032)
						)
					)
					(width 0)
					(fill yes)
				)
			)
		)
	)
	(footprint ""
		(layer "B.Cu")
		(at 318.008 -164.338 -90)
		(property "Reference" "R245"
			(at 0 0 90)
			(layer "B.SilkS")
			(hide yes)
			(effects
				(font
					(size 1.27 1.27)
				)
				(justify mirror)
			)
		)
		(property "Value" "0R2J-2-GP"
			(at -0.064008 -3.993896 270)
			(unlocked yes)
			(layer "B.Fab")
			(hide yes)
			(effects
				(font
					(size 1.016 1.016)
					(thickness 0.1524)
				)
				(justify mirror)
			)
		)
		(property "Device Type" "R402H16"
			(at -0.064008 -5.517896 270)
			(unlocked yes)
			(layer "B.Fab")
			(hide yes)
			(effects
				(font
					(size 1.016 1.016)
					(thickness 0.1524)
				)
				(justify mirror)
			)
		)
		(duplicate_pad_numbers_are_jumpers no)
		(fp_line
			(start -0.508 -0.9398)
			(end 0.508 -0.9398)
			(stroke
				(width 0.1524)
				(type default)
			)
			(layer "B.SilkS")
		)
		(fp_line
			(start 0.508 -0.9398)
			(end 0.508 0.9398)
			(stroke
				(width 0.1524)
				(type default)
			)
			(layer "B.SilkS")
		)
		(fp_rect
			(start 0.508 0.9398)
			(end -0.508 -0.9398)
			(stroke
				(width 0)
				(type default)
			)
			(fill no)
			(layer "B.CrtYd")
		)
		(fp_rect
			(start 0.508 0.9398)
			(end -0.508 -0.9398)
			(stroke
				(width 0)
				(type default)
			)
			(fill no)
			(layer "B.Fab")
		)
		(pad "1" smd custom
			(at 0 -0.4445 90)
			(size 0.1397 0.1397)
			(layers "B.Cu" "B.Mask" "B.Paste")
			(net "NIC_SMBUS_SDA")
			(options
				(clearance outline)
				(anchor circle)
			)
			(primitives
				(gr_poly
					(pts
						(arc
							(start -0.1778 0.2794)
							(mid -0.249642 0.249642)
							(end -0.2794 0.1778)
						)
						(arc
							(start -0.2794 -0.1778)
							(mid -0.249642 -0.249642)
							(end -0.1778 -0.2794)
						)
						(arc
							(start 0.1778 -0.2794)
							(mid 0.249642 -0.249642)
							(end 0.2794 -0.1778)
						)
						(arc
							(start 0.2794 0.1778)
							(mid 0.249642 0.249642)
							(end 0.1778 0.2794)
						)
					)
					(width 0)
					(fill yes)
				)
			)
		)
		(pad "2" smd custom
			(at 0 0.4445 90)
			(size 0.1397 0.1397)
			(layers "B.Cu" "B.Mask" "B.Paste")
			(net "BMC0_SMB4_DAT")
			(options
				(clearance outline)
				(anchor circle)
			)
			(primitives
				(gr_poly
					(pts
						(arc
							(start -0.1778 0.2794)
							(mid -0.249642 0.249642)
							(end -0.2794 0.1778)
						)
						(arc
							(start -0.2794 -0.1778)
							(mid -0.249642 -0.249642)
							(end -0.1778 -0.2794)
						)
						(arc
							(start 0.1778 -0.2794)
							(mid 0.249642 -0.249642)
							(end 0.2794 -0.1778)
						)
						(arc
							(start 0.2794 0.1778)
							(mid 0.249642 0.249642)
							(end 0.1778 0.2794)
						)
					)
					(width 0)
					(fill yes)
				)
			)
		)
	)
	(footprint ""
		(layer "B.Cu")
		(at 118.688612 -222.885 180)
		(property "Reference" "SR887"
			(at 0 0 0)
			(layer "B.SilkS")
			(hide yes)
			(effects
				(font
					(size 1.27 1.27)
				)
				(justify mirror)
			)
		)
		(property "Value" "0R2J-2-GP"
			(at -0.064008 -3.993896 180)
			(unlocked yes)
			(layer "B.Fab")
			(hide yes)
			(effects
				(font
					(size 1.016 1.016)
					(thickness 0.1524)
				)
				(justify mirror)
			)
		)
		(property "Device Type" "R402H16"
			(at -0.064008 -5.517896 180)
			(unlocked yes)
			(layer "B.Fab")
			(hide yes)
			(effects
				(font
					(size 1.016 1.016)
					(thickness 0.1524)
				)
				(justify mirror)
			)
		)
		(duplicate_pad_numbers_are_jumpers no)
		(fp_line
			(start 0.508 -0.9398)
			(end 0.508 0.9398)
			(stroke
				(width 0.1524)
				(type default)
			)
			(layer "B.SilkS")
		)
		(fp_line
			(start -0.508 -0.9398)
			(end 0.508 -0.9398)
			(stroke
				(width 0.1524)
				(type default)
			)
			(layer "B.SilkS")
		)
		(fp_rect
			(start 0.508 0.9398)
			(end -0.508 -0.9398)
			(stroke
				(width 0)
				(type default)
			)
			(fill no)
			(layer "B.CrtYd")
		)
		(fp_rect
			(start 0.508 0.9398)
			(end -0.508 -0.9398)
			(stroke
				(width 0)
				(type default)
			)
			(fill no)
			(layer "B.Fab")
		)
		(pad "1" smd custom
			(at 0 -0.4445)
			(size 0.1397 0.1397)
			(layers "B.Cu" "B.Mask" "B.Paste")
			(net "SAS_GF_EXP_RX_DP7")
			(options
				(clearance outline)
				(anchor circle)
			)
			(primitives
				(gr_poly
					(pts
						(arc
							(start -0.1778 0.2794)
							(mid -0.249642 0.249642)
							(end -0.2794 0.1778)
						)
						(arc
							(start -0.2794 -0.1778)
							(mid -0.249642 -0.249642)
							(end -0.1778 -0.2794)
						)
						(arc
							(start 0.1778 -0.2794)
							(mid 0.249642 -0.249642)
							(end 0.2794 -0.1778)
						)
						(arc
							(start 0.2794 0.1778)
							(mid 0.249642 0.249642)
							(end 0.1778 0.2794)
						)
					)
					(width 0)
					(fill yes)
				)
			)
		)
		(pad "2" smd custom
			(at 0 0.4445)
			(size 0.1397 0.1397)
			(layers "B.Cu" "B.Mask" "B.Paste")
			(net "REDV_RX7_P")
			(options
				(clearance outline)
				(anchor circle)
			)
			(primitives
				(gr_poly
					(pts
						(arc
							(start -0.1778 0.2794)
							(mid -0.249642 0.249642)
							(end -0.2794 0.1778)
						)
						(arc
							(start -0.2794 -0.1778)
							(mid -0.249642 -0.249642)
							(end -0.1778 -0.2794)
						)
						(arc
							(start 0.1778 -0.2794)
							(mid 0.249642 -0.249642)
							(end 0.2794 -0.1778)
						)
						(arc
							(start 0.2794 0.1778)
							(mid 0.249642 0.249642)
							(end 0.1778 0.2794)
						)
					)
					(width 0)
					(fill yes)
				)
			)
		)
	)
	(footprint ""
		(layer "B.Cu")
		(at 167.630348 -118.354856 -90)
		(property "Reference" "PC184"
			(at 0 0 90)
			(layer "B.SilkS")
			(hide yes)
			(effects
				(font
					(size 1.27 1.27)
				)
				(justify mirror)
			)
		)
		(property "Value" "SC4D7U25V5KX-1-GP"
			(at 0.0762 -6.1214 270)
			(unlocked yes)
			(layer "B.Fab")
			(hide yes)
			(effects
				(font
					(size 1.016 1.016)
					(thickness 0.1524)
				)
				(justify mirror)
			)
		)
		(property "Device Type" "C805H58"
			(at 0.0762 -8.1534 270)
			(unlocked yes)
			(layer "B.Fab")
			(hide yes)
			(effects
				(font
					(size 1.016 1.016)
					(thickness 0.1524)
				)
				(justify mirror)
			)
		)
		(duplicate_pad_numbers_are_jumpers no)
		(fp_line
			(start -0.635 0)
			(end 0.635 0)
			(stroke
				(width 0.508)
				(type default)
			)
			(layer "B.SilkS")
		)
		(fp_rect
			(start 0.9652 1.778)
			(end -0.9652 -1.778)
			(stroke
				(width 0)
				(type default)
			)
			(fill no)
			(layer "B.CrtYd")
		)
		(fp_poly
			(pts
				(xy 0.9652 -1.778) (xy -0.9652 -1.778) (xy -0.9652 1.778) (xy 0.9652 1.778)
			)
			(stroke
				(width 0)
				(type default)
			)
			(fill no)
			(layer "B.Fab")
		)
		(pad "1" smd rect
			(at 0 -0.9652 90)
			(size 1.397 1.143)
			(layers "B.Cu" "B.Mask" "B.Paste")
			(net "P0V9_E_VDD")
		)
		(pad "2" smd rect
			(at 0 0.9652 90)
			(size 1.397 1.143)
			(layers "B.Cu" "B.Mask" "B.Paste")
			(net "GND")
		)
	)
)
